# T6G (Grand Teton) — schematic netlist excerpt (pin names and nets, part order shuffled) for the footprints in the layout excerpt that follows; sources: Cadence DE-HDL packaged netlist, KiCad conversion of 04192023_DAF0TMB3IC0_F0TG_MB_C_brd_V02_OCP.brd

U237  PI3EQX12902AZLEX  IC  pkg TQFN30_TH_0-4_4-5X2-5  page 111
  VDD1  = P3V3_AUX
  AIP  = P2E_MB_BMC_TX_C_R1_DP<0>
  AIN  = P2E_MB_BMC_TX_C_R1_DN<0>
  GND1  = GND
  \test#\  = PU_TEST
  GND2  = GND
  GND3  = GND
  BON  = P2E_MB_BMC_RX_BUF_C_DN<0>
  BOP  = P2E_MB_BMC_RX_BUF_C_DP<0>
  VDD2  = P3V3_AUX
  \en#\  = FM_P2E_EN_N
  SWB  = FM_P2E_SWB
  GND4  = GND
  FGB  = FM_P2E_FGB
  EQB1  = FM_P2E_EQB1
  VDD3  = P3V3_AUX
  BIP  = P2E_MB_BMC_RX_R1_DP<0>
  BIN  = P2E_MB_BMC_RX_R1_DN<0>
  GND5  = GND
  EQB0  = FM_P2E_EQB0
  EQA0  = FM_P2E_EQA0
  GND6  = GND
  AON  = P2E_MB_BMC_TX_BUF_DN<0>
  AOP  = P2E_MB_BMC_TX_BUF_DP<0>
  VDD4  = P3V3_AUX
  EQA1  = FM_P2E_EQA1
  FGA  = FM_P2E_FGA
  GND7  = GND
  SWA  = FM_P2E_SWA
  MODE  = FM_P2E_MODE
  GND_TH  = GND

(kicad_pcb
	(version 20260206)
	(generator "pcbnew")
	(generator_version "10.0")
	(general
		(thickness 1.6)
		(legacy_teardrops no)
	)
	(paper "A4")
	(title_block
		(title "04192023_DAF0TMB3IC0_F0TG_MB_C_brd_V02_OCP.brd")
		(comment 1 "Grand Teton / footprint 222 of 8354 (U237), pads 1-31 of 31")
	)
	(layers
		(0 "F.Cu" signal "TOP")
		(4 "In1.Cu" signal "GND")
		(6 "In2.Cu" signal "IN1")
		(8 "In3.Cu" signal "GND1")
		(10 "In4.Cu" signal "IN2")
		(12 "In5.Cu" signal "GND2")
		(14 "In6.Cu" signal "IN3")
		(16 "In7.Cu" signal "GND3")
		(18 "In8.Cu" signal "VCC")
		(20 "In9.Cu" signal "VCC1")
		(22 "In10.Cu" signal "GND4")
		(24 "In11.Cu" signal "IN4")
		(26 "In12.Cu" signal "GND5")
		(28 "In13.Cu" signal "IN5")
		(30 "In14.Cu" signal "GND6")
		(32 "In15.Cu" signal "IN6")
		(34 "In16.Cu" signal "GND7")
		(2 "B.Cu" signal "BOTTOM")
		(9 "F.Adhes" user "F.Adhesive")
		(11 "B.Adhes" user "B.Adhesive")
		(13 "F.Paste" user "Package Geometry/Pastemask Top")
		(15 "B.Paste" user "Package Geometry/Pastemask Bottom")
		(5 "F.SilkS" user "Ref Des/Silkscreen Top")
		(7 "B.SilkS" user "Ref Des/Silkscreen Bottom")
		(1 "F.Mask" user "Board Geometry/Soldermask Top")
		(3 "B.Mask" user "Board Geometry/Soldermask Bottom")
		(17 "Dwgs.User" user "User.Drawings")
		(19 "Cmts.User" user "User.Comments")
		(21 "Eco1.User" user "User.Eco1")
		(23 "Eco2.User" user "User.Eco2")
		(25 "Edge.Cuts" user "Board Geometry/Outline")
		(27 "Margin" user)
		(31 "F.CrtYd" user "Package Geometry/Place Bound Top")
		(29 "B.CrtYd" user "Package Geometry/Place Bound Bottom")
		(35 "F.Fab" user "Ref Des/Assembly Top")
		(33 "B.Fab" user "Ref Des/Assembly Bottom")
	)
	(footprint ""
		(layer "F.Cu")
		(at 34.252662 -424.710098 180)
		(property "Reference" "U237"
			(at -6.560312 3.07086 0)
			(unlocked yes)
			(layer "F.SilkS")
			(effects
				(font
					(size 0.7874 0.5842)
					(thickness 0.1524)
				)
				(justify left)
			)
		)
		(property "Value" ""
			(at 0 0 180)
			(layer "F.Fab")
			(effects
				(font
					(size 1.27 1.27)
				)
			)
		)
		(duplicate_pad_numbers_are_jumpers no)
		(pad "1" smd circle
			(at -1.249934 -1.800098 90)
			(size 0 0)
			(layers "F.Cu" "F.Mask" "F.Paste")
			(net "P3V3_AUX")
		)
		(pad "2" smd circle
			(at -1.249934 -1.400048 90)
			(size 0 0)
			(layers "F.Cu" "F.Mask" "F.Paste")
			(net "P2E_MB_BMC_TX_C_R1_DP<0>")
		)
		(pad "3" smd circle
			(at -1.249934 -0.999998 90)
			(size 0 0)
			(layers "F.Cu" "F.Mask" "F.Paste")
			(net "P2E_MB_BMC_TX_C_R1_DN<0>")
		)
		(pad "4" smd circle
			(at -1.249934 -0.599948 90)
			(size 0 0)
			(layers "F.Cu" "F.Mask" "F.Paste")
			(net "GND")
		)
		(pad "5" smd circle
			(at -1.249934 -0.199898 90)
			(size 0 0)
			(layers "F.Cu" "F.Mask" "F.Paste")
			(net "PU_TEST")
		)
		(pad "6" smd circle
			(at -1.249934 0.199898 90)
			(size 0 0)
			(layers "F.Cu" "F.Mask" "F.Paste")
			(net "GND")
		)
		(pad "7" smd circle
			(at -1.249934 0.599948 90)
			(size 0 0)
			(layers "F.Cu" "F.Mask" "F.Paste")
			(net "GND")
		)
		(pad "8" smd circle
			(at -1.249934 0.999998 90)
			(size 0 0)
			(layers "F.Cu" "F.Mask" "F.Paste")
			(net "P2E_MB_BMC_RX_BUF_C_DN<0>")
		)
		(pad "9" smd circle
			(at -1.249934 1.400048 90)
			(size 0 0)
			(layers "F.Cu" "F.Mask" "F.Paste")
			(net "P2E_MB_BMC_RX_BUF_C_DP<0>")
		)
		(pad "10" smd circle
			(at -1.249934 1.800098 90)
			(size 0 0)
			(layers "F.Cu" "F.Mask" "F.Paste")
			(net "P3V3_AUX")
		)
		(pad "11" smd circle
			(at -0.8001 2.249932 180)
			(size 0 0)
			(layers "F.Cu" "F.Mask" "F.Paste")
			(net "FM_P2E_EN_N")
		)
		(pad "12" smd circle
			(at -0.40005 2.249932 180)
			(size 0 0)
			(layers "F.Cu" "F.Mask" "F.Paste")
			(net "FM_P2E_SWB")
		)
		(pad "13" smd circle
			(at 0 2.249932 180)
			(size 0 0)
			(layers "F.Cu" "F.Mask" "F.Paste")
			(net "GND")
		)
		(pad "14" smd circle
			(at 0.40005 2.249932 180)
			(size 0 0)
			(layers "F.Cu" "F.Mask" "F.Paste")
			(net "FM_P2E_FGB")
		)
		(pad "15" smd circle
			(at 0.8001 2.249932 180)
			(size 0 0)
			(layers "F.Cu" "F.Mask" "F.Paste")
			(net "FM_P2E_EQB1")
		)
		(pad "16" smd circle
			(at 1.249934 1.800098 270)
			(size 0 0)
			(layers "F.Cu" "F.Mask" "F.Paste")
			(net "P3V3_AUX")
		)
		(pad "17" smd circle
			(at 1.249934 1.400048 270)
			(size 0 0)
			(layers "F.Cu" "F.Mask" "F.Paste")
			(net "P2E_MB_BMC_RX_R1_DP<0>")
		)
		(pad "18" smd circle
			(at 1.249934 0.999998 270)
			(size 0 0)
			(layers "F.Cu" "F.Mask" "F.Paste")
			(net "P2E_MB_BMC_RX_R1_DN<0>")
		)
		(pad "19" smd circle
			(at 1.249934 0.599948 270)
			(size 0 0)
			(layers "F.Cu" "F.Mask" "F.Paste")
			(net "GND")
		)
		(pad "20" smd circle
			(at 1.249934 0.199898 270)
			(size 0 0)
			(layers "F.Cu" "F.Mask" "F.Paste")
			(net "FM_P2E_EQB0")
		)
		(pad "21" smd circle
			(at 1.249934 -0.199898 270)
			(size 0 0)
			(layers "F.Cu" "F.Mask" "F.Paste")
			(net "FM_P2E_EQA0")
		)
		(pad "22" smd circle
			(at 1.249934 -0.599948 270)
			(size 0 0)
			(layers "F.Cu" "F.Mask" "F.Paste")
			(net "GND")
		)
		(pad "23" smd circle
			(at 1.249934 -0.999998 270)
			(size 0 0)
			(layers "F.Cu" "F.Mask" "F.Paste")
			(net "P2E_MB_BMC_TX_BUF_DN<0>")
		)
		(pad "24" smd circle
			(at 1.249934 -1.400048 270)
			(size 0 0)
			(layers "F.Cu" "F.Mask" "F.Paste")
			(net "P2E_MB_BMC_TX_BUF_DP<0>")
		)
		(pad "25" smd circle
			(at 1.249934 -1.800098 270)
			(size 0 0)
			(layers "F.Cu" "F.Mask" "F.Paste")
			(net "P3V3_AUX")
		)
		(pad "26" smd circle
			(at 0.8001 -2.249932)
			(size 0 0)
			(layers "F.Cu" "F.Mask" "F.Paste")
			(net "FM_P2E_EQA1")
		)
		(pad "27" smd circle
			(at 0.40005 -2.249932)
			(size 0 0)
			(layers "F.Cu" "F.Mask" "F.Paste")
			(net "FM_P2E_FGA")
		)
		(pad "28" smd circle
			(at 0 -2.249932)
			(size 0 0)
			(layers "F.Cu" "F.Mask" "F.Paste")
			(net "GND")
		)
		(pad "29" smd circle
			(at -0.40005 -2.249932)
			(size 0 0)
			(layers "F.Cu" "F.Mask" "F.Paste")
			(net "FM_P2E_SWA")
		)
		(pad "30" smd circle
			(at -0.8001 -2.249932)
			(size 0 0)
			(layers "F.Cu" "F.Mask" "F.Paste")
			(net "FM_P2E_MODE")
		)
		(pad "TH" smd rect
			(at 0 0 180)
			(size 1.2192 3.2004)
			(layers "F.Cu" "F.Mask" "F.Paste")
			(net "GND")
		)
	)
)
